# S9S_MB_2U (Grand Teton) — schematic netlist excerpt (pin names and nets, part order shuffled) for the footprints in the layout excerpt that follows; sources: Cadence DE-HDL packaged netlist, KiCad conversion of 03242023_DA0F0TMBIJ0_F0T_Motherboard_J_brd_V01_OCP.brd

J15  SCONN288_ADR50017P130CC  SCONN288_ADR50017-P130CC IO  pkg DDR288S_1-1VXB  page 96
  VIN_BULK0  = P12V_S3_AUX_CPU0_NVDIMM
  RFU0  = TP_CHH_CPU0_DIMM1_FRU_0
  VIN_MGMT  = P3V3_AUX
  HSCL  = I3C_SPD_DDREFGH_CPU0_LVC1_SCL_6
  HSDA  = I3C_SPD_DDREFGH_CPU0_LVC1_SDA
  VSS0  = GND
  DQ0_A  = M_H_CPU0_SA_DQ<0>
  VSS1  = GND
  DQ1_A  = M_H_CPU0_SA_DQ<1>
  VSS2  = GND
  DQS0_A_T  = M_H_CPU0_SA_DQS_DP<0>
  DQS0_A_C  = M_H_CPU0_SA_DQS_DN<0>
  VSS3  = GND
  DQ4_A  = M_H_CPU0_SA_DQ<4>
  VSS4  = GND
  DQ5_A  = M_H_CPU0_SA_DQ<5>
  VSS5  = GND
  DQ8_A  = M_H_CPU0_SA_DQ<8>
  VSS6  = GND
  DQ9_A  = M_H_CPU0_SA_DQ<9>
  VSS7  = GND
  DQS1_A_T  = M_H_CPU0_SA_DQS_DP<1>
  DQS1_A_C  = M_H_CPU0_SA_DQS_DN<1>
  VSS8  = GND
  DQ12_A  = M_H_CPU0_SA_DQ<12>
  VSS9  = GND
  DQ13_A  = M_H_CPU0_SA_DQ<13>
  VSS10  = GND
  DQ16_A  = M_H_CPU0_SA_DQ<16>
  VSS11  = GND
  DQ17_A  = M_H_CPU0_SA_DQ<17>
  VSS12  = GND
  DQS2_A_T  = M_H_CPU0_SA_DQS_DP<2>
  DQS2_A_C  = M_H_CPU0_SA_DQS_DN<2>
  VSS13  = GND
  DQ20_A  = M_H_CPU0_SA_DQ<20>
  VSS14  = GND
  DQ21_A  = M_H_CPU0_SA_DQ<21>
  VSS15  = GND
  DQ24_A  = M_H_CPU0_SA_DQ<24>
  VSS16  = GND
  DQ25_A  = M_H_CPU0_SA_DQ<25>
  VSS17  = GND
  DQS3_A_T  = M_H_CPU0_SA_DQS_DP<3>
  DQS3_A_C  = M_H_CPU0_SA_DQS_DN<3>
  VSS18  = GND
  DQ28_A  = M_H_CPU0_SA_DQ<28>
  VSS19  = GND
  DQ29_A  = M_H_CPU0_SA_DQ<29>
  VSS20  = GND
  CB0_A  = M_H_CPU0_SA_CB<0>
  VSS21  = GND
  CB1_A  = M_H_CPU0_SA_CB<1>
  VSS22  = GND
  DQS4_A_T  = M_H_CPU0_SA_DQS_DP<4>
  DQS4_A_C  = M_H_CPU0_SA_DQS_DN<4>
  VSS23  = GND
  CB4_A  = M_H_CPU0_SA_CB<4>
  VSS24  = GND
  CB5_A  = M_H_CPU0_SA_CB<5>
  VSS25  = GND
  ALERT_N  = M_H_CPU0_ALERT_N
  VSS26  = GND
  CS0_A_N  = M_H_CPU0_SA_CS_N<0>
  VSS27  = GND
  CA0_A  = M_H_CPU0_SA_CA<0>
  VSS28  = GND
  CA2_A  = M_H_CPU0_SA_CA<2>
  VSS29  = GND
  CA4_A  = M_H_CPU0_SA_CA<4>
  VSS30  = GND
  CA6_A  = M_H_CPU0_SA_CA<6>
  VSS31  = GND
  PAR_A  = M_H_CPU0_SA_PAR
  VSS32  = GND
  CA0_B  = M_H_CPU0_SB_CA<0>
  VSS33  = GND
  CA2_B  = M_H_CPU0_SB_CA<2>
  VSS34  = GND
  CA4_B  = M_H_CPU0_SB_CA<4>
  VSS35  = GND
  CA6_B  = M_H_CPU0_SB_CA<6>
  VSS36  = GND
  CS0_B_N  = M_H_CPU0_SB_CS_N<0>
  VSS37  = GND
  \lbd||rsp_a_n\  = M_H_CPU0_SA_RSP<0>
  \lbs||rsp_b_n\  = M_H_CPU0_SB_RSP<0>
  VSS38  = GND
  CB4_B  = M_H_CPU0_SB_CB<4>
  VSS39  = GND
  CB5_B  = M_H_CPU0_SB_CB<5>
  VSS40  = GND
  \dqs9_b_t||tdqs9_b_t||dbi4_b_n\  = M_H_CPU0_SB_DQS_DP<9>
  \dqs9_b_c||tdqs9_b_c\  = M_H_CPU0_SB_DQS_DN<9>
  VSS41  = GND
  CB0_B  = M_H_CPU0_SB_CB<0>
  VSS42  = GND
  CB1_B  = M_H_CPU0_SB_CB<1>
  VSS43  = GND
  DQ0_B  = M_H_CPU0_SB_DQ<0>
  VSS44  = GND
  DQ1_B  = M_H_CPU0_SB_DQ<1>
  VSS45  = GND
  DQS0_B_T  = M_H_CPU0_SB_DQS_DP<0>
  DQS0_B_C  = M_H_CPU0_SB_DQS_DN<0>
  VSS46  = GND
  DQ4_B  = M_H_CPU0_SB_DQ<4>
  VSS47  = GND
  DQ5_B  = M_H_CPU0_SB_DQ<5>
  VSS48  = GND
  DQ8_B  = M_H_CPU0_SB_DQ<8>
  VSS49  = GND
  DQ9_B  = M_H_CPU0_SB_DQ<9>
  VSS50  = GND
  DQS1_B_T  = M_H_CPU0_SB_DQS_DP<1>
  DQS1_B_C  = M_H_CPU0_SB_DQS_DN<1>
  VSS51  = GND
  DQ12_B  = M_H_CPU0_SB_DQ<12>
  VSS52  = GND
  DQ13_B  = M_H_CPU0_SB_DQ<13>
  VSS53  = GND
  DQ16_B  = M_H_CPU0_SB_DQ<16>
  VSS54  = GND
  DQ17_B  = M_H_CPU0_SB_DQ<17>
  VSS55  = GND
  DQS2_B_T  = M_H_CPU0_SB_DQS_DP<2>
  DQS2_B_C  = M_H_CPU0_SB_DQS_DN<2>
  VSS56  = GND
  DQ20_B  = M_H_CPU0_SB_DQ<20>
  VSS57  = GND
  DQ21_B  = M_H_CPU0_SB_DQ<21>
  VSS58  = GND
  DQ24_B  = M_H_CPU0_SB_DQ<24>
  VSS59  = GND
  DQ25_B  = M_H_CPU0_SB_DQ<25>
  VSS60  = GND
  DQS3_B_T  = M_H_CPU0_SB_DQS_DP<3>
  DQS3_B_C  = M_H_CPU0_SB_DQS_DN<3>
  VSS61  = GND
  DQ28_B  = M_H_CPU0_SB_DQ<28>
  VSS62  = GND
  DQ29_B  = M_H_CPU0_SB_DQ<29>
  VSS63  = GND
  RFU1  = TP_CHH_CPU0_DIMM1_FRU_1
  VIN_BULK1  = P12V_S3_AUX_CPU0_NVDIMM
  VIN_BULK2  = P12V_S3_AUX_CPU0_NVDIMM
  \pwr_good||fail_n\  = PWRGD_CHH_CPU0_DIMM1
  HSA  = PD_CHH_CPU0_DIMM1_SAA
  RFU2  = TP_CHH_CPU0_DIMM1_FRU_2
  RFU3  = TP_CHH_CPU0_DIMM1_FRU_3
  VSS64  = GND
  DQ2_A  = M_H_CPU0_SA_DQ<2>
  VSS65  = GND
  DQ3_A  = M_H_CPU0_SA_DQ<3>
  VSS66  = GND
  \dqs5_a_c||tdqs5_a_c||dqs5_a_t||tdqs5_a_t\  = M_H_CPU0_SA_DQS_DN<5>
  \dqs5_a_t||tdqs5_a_t\  = M_H_CPU0_SA_DQS_DP<5>
  VSS67  = GND
  DQ6_A  = M_H_CPU0_SA_DQ<6>
  VSS68  = GND
  DQ7_A  = M_H_CPU0_SA_DQ<7>
  VSS69  = GND
  DQ10_A  = M_H_CPU0_SA_DQ<10>
  VSS70  = GND
  DQ11_A  = M_H_CPU0_SA_DQ<11>
  VSS71  = GND
  \dqs6_a_c||tdqs6_a_c||dqs6_a_t||tdqs6_a_t\  = M_H_CPU0_SA_DQS_DN<6>
  \dqs6_a_t||tdqs6_a_t\  = M_H_CPU0_SA_DQS_DP<6>
  VSS72  = GND
  DQ14_A  = M_H_CPU0_SA_DQ<14>
  VSS73  = GND
  DQ15_A  = M_H_CPU0_SA_DQ<15>
  VSS74  = GND
  DQ18_A  = M_H_CPU0_SA_DQ<18>
  VSS75  = GND
  DQ19_A  = M_H_CPU0_SA_DQ<19>
  VSS76  = GND
  \dqs7_a_c||tdqs7_a_c\  = M_H_CPU0_SA_DQS_DN<7>
  \dqs7_a_t||tdqs7_a_t\  = M_H_CPU0_SA_DQS_DP<7>
  VSS77  = GND
  DQ22_A  = M_H_CPU0_SA_DQ<22>
  VSS78  = GND
  DQ23_A  = M_H_CPU0_SA_DQ<23>
  VSS79  = GND
  DQ26_A  = M_H_CPU0_SA_DQ<26>
  VSS80  = GND
  DQ27_A  = M_H_CPU0_SA_DQ<27>
  VSS81  = GND
  \dqs8_a_c||tdqs8_a_c\  = M_H_CPU0_SA_DQS_DN<8>
  \dqs8_a_t||tdqs8_a_t\  = M_H_CPU0_SA_DQS_DP<8>
  VSS82  = GND
  DQ30_A  = M_H_CPU0_SA_DQ<30>
  VSS83  = GND
  DQ31_A  = M_H_CPU0_SA_DQ<31>
  VSS84  = GND
  CB2_A  = M_H_CPU0_SA_CB<2>
  VSS85  = GND
  CB3_A  = M_H_CPU0_SA_CB<3>
  VSS86  = GND
  \dqs9_a_c||tdqs9_a_c\  = M_H_CPU0_SA_DQS_DN<9>
  \dqs9_a_t||tdqs9_a_t\  = M_H_CPU0_SA_DQS_DP<9>
  VSS87  = GND
  CB6_A  = M_H_CPU0_SA_CB<6>
  VSS88  = GND
  CB7_A  = M_H_CPU0_SA_CB<7>
  VSS89  = GND
  RESET_N  = RST_M_GH_CPU0_FPGA_N
  VSS90  = GND
  CS1_A_N  = M_H_CPU0_SA_CS_N<1>
  VSS91  = GND
  CA1_A  = M_H_CPU0_SA_CA<1>
  VSS92  = GND
  CA3_A  = M_H_CPU0_SA_CA<3>
  VSS93  = GND
  CA5_A  = M_H_CPU0_SA_CA<5>
  VSS94  = GND
  CK_T  = M_H_CPU0_CLK_DP<0>
  CK_C  = M_H_CPU0_CLK_DN<0>
  VSS95  = GND
  RFU4  = TP_CHH_CPU0_DIMM1_FRU_4
  CA1_B  = M_H_CPU0_SB_CA<1>
  VSS96  = GND
  CA3_B  = M_H_CPU0_SB_CA<3>
  VSS97  = GND
  CA5_B  = M_H_CPU0_SB_CA<5>
  VSS98  = GND
  PAR_B  = M_H_CPU0_SB_PAR
  VSS99  = GND
  CS1_B_N  = M_H_CPU0_SB_CS_N<1>
  VSS100  = GND
  RFU5  = TP_CHH_CPU0_DIMM1_FRU_5
  RFU6  = TP_CHH_CPU0_DIMM1_FRU_6
  VSS101  = GND
  CB6_B  = M_H_CPU0_SB_CB<6>
  VSS102  = GND
  CB7_B  = M_H_CPU0_SB_CB<7>
  VSS103  = GND
  DQS4_B_C  = M_H_CPU0_SB_DQS_DN<4>
  DQS4_B_T  = M_H_CPU0_SB_DQS_DP<4>
  VSS104  = GND
  CB2_B  = M_H_CPU0_SB_CB<2>
  VSS105  = GND
  CB3_B  = M_H_CPU0_SB_CB<3>
  VSS106  = GND
  DQ2_B  = M_H_CPU0_SB_DQ<2>
  VSS107  = GND
  DQ3_B  = M_H_CPU0_SB_DQ<3>
  VSS108  = GND
  \dqs5_b_c||tdqs5_b_c\  = M_H_CPU0_SB_DQS_DN<5>
  \dqs5_b_t||tdqs5_b_t\  = M_H_CPU0_SB_DQS_DP<5>
  VSS109  = GND
  DQ6_B  = M_H_CPU0_SB_DQ<6>
  VSS110  = GND
  DQ7_B  = M_H_CPU0_SB_DQ<7>
  VSS111  = GND
  DQ10_B  = M_H_CPU0_SB_DQ<10>
  VSS112  = GND
  DQ11_B  = M_H_CPU0_SB_DQ<11>
  VSS113  = GND
  \dqs6_b_c||tdqs6_b_c\  = M_H_CPU0_SB_DQS_DN<6>
  \dqs6_b_t||tdqs6_b_t\  = M_H_CPU0_SB_DQS_DP<6>
  VSS114  = GND
  DQ14_B  = M_H_CPU0_SB_DQ<14>
  VSS115  = GND
  DQ15_B  = M_H_CPU0_SB_DQ<15>
  VSS116  = GND
  DQ18_B  = M_H_CPU0_SB_DQ<18>
  VSS117  = GND
  DQ19_B  = M_H_CPU0_SB_DQ<19>
  VSS118  = GND
  \dqs7_b_c||tdqs7_b_c\  = M_H_CPU0_SB_DQS_DN<7>
  \dqs7_b_t||tdqs7_b_t\  = M_H_CPU0_SB_DQS_DP<7>
  VSS119  = GND
  DQ22_B  = M_H_CPU0_SB_DQ<22>
  VSS120  = GND
  DQ23_B  = M_H_CPU0_SB_DQ<23>
  VSS121  = GND
  DQ26_B  = M_H_CPU0_SB_DQ<26>
  VSS122  = GND
  DQ27_B  = M_H_CPU0_SB_DQ<27>
  VSS123  = GND
  \dqs8_b_c||tdqs8_b_c\  = M_H_CPU0_SB_DQS_DN<8>
  \dqs8_b_t||tdqs8_b_t\  = M_H_CPU0_SB_DQS_DP<8>
  VSS124  = GND
  DQ30_B  = M_H_CPU0_SB_DQ<30>
  VSS125  = GND
  DQ31_B  = M_H_CPU0_SB_DQ<31>
  VSS126  = GND
  G1  = GND
  G2  = GND
  G3  = GND

(kicad_pcb
	(version 20260206)
	(generator "pcbnew")
	(generator_version "10.0")
	(general
		(thickness 1.6)
		(legacy_teardrops no)
	)
	(paper "A4")
	(title_block
		(title "03242023_DA0F0TMBIJ0_F0T_Motherboard_J_brd_V01_OCP.brd")
		(comment 1 "Grand Teton / footprint 2194 of 6105 (J15), pads 92-137 of 291")
	)
	(layers
		(0 "F.Cu" signal "TOP")
		(4 "In1.Cu" signal "GND")
		(6 "In2.Cu" signal "IN1")
		(8 "In3.Cu" signal "GND1")
		(10 "In4.Cu" signal "IN2")
		(12 "In5.Cu" signal "GND2")
		(14 "In6.Cu" signal "IN3")
		(16 "In7.Cu" signal "GND3")
		(18 "In8.Cu" signal "VCC")
		(20 "In9.Cu" signal "VCC1")
		(22 "In10.Cu" signal "GND4")
		(24 "In11.Cu" signal "IN4")
		(26 "In12.Cu" signal "GND5")
		(28 "In13.Cu" signal "IN5")
		(30 "In14.Cu" signal "GND6")
		(32 "In15.Cu" signal "IN6")
		(34 "In16.Cu" signal "GND7")
		(2 "B.Cu" signal "BOTTOM")
		(9 "F.Adhes" user "F.Adhesive")
		(11 "B.Adhes" user "B.Adhesive")
		(13 "F.Paste" user "Package Geometry/Pastemask Top")
		(15 "B.Paste" user "Package Geometry/Pastemask Bottom")
		(5 "F.SilkS" user "Ref Des/Silkscreen Top")
		(7 "B.SilkS" user "Ref Des/Silkscreen Bottom")
		(1 "F.Mask" user "Board Geometry/Soldermask Top")
		(3 "B.Mask" user "Board Geometry/Soldermask Bottom")
		(17 "Dwgs.User" user "User.Drawings")
		(19 "Cmts.User" user "User.Comments")
		(21 "Eco1.User" user "User.Eco1")
		(23 "Eco2.User" user "User.Eco2")
		(25 "Edge.Cuts" user "Board Geometry/Outline")
		(27 "Margin" user)
		(31 "F.CrtYd" user "Package Geometry/Place Bound Top")
		(29 "B.CrtYd" user "Package Geometry/Place Bound Bottom")
		(35 "F.Fab" user "Ref Des/Assembly Top")
		(33 "B.Fab" user "Ref Des/Assembly Bottom")
	)
	(footprint ""
		(layer "F.Cu")
		(at 461.609948 -258.091686)
		(property "Reference" "J15"
			(at 3.019552 -81.652872 0)
			(unlocked yes)
			(layer "F.SilkS")
			(effects
				(font
					(size 0.7874 0.5842)
					(thickness 0.1524)
				)
				(justify left)
			)
		)
		(property "Value" ""
			(at 0 0 0)
			(layer "F.Fab")
			(effects
				(font
					(size 1.27 1.27)
				)
			)
		)
		(duplicate_pad_numbers_are_jumpers no)
		(pad "92" smd rect
			(at -2.050034 19.12493 270)
			(size 0.519938 1.4986)
			(layers "F.Cu" "F.Mask" "F.Paste")
			(net "GND")
		)
		(pad "93" smd rect
			(at -2.050034 19.975068 270)
			(size 0.519938 1.4986)
			(layers "F.Cu" "F.Mask" "F.Paste")
			(net "M_H_CPU0_SB_DQS_DP<9>")
		)
		(pad "94" smd rect
			(at -2.050034 20.824952 270)
			(size 0.519938 1.4986)
			(layers "F.Cu" "F.Mask" "F.Paste")
			(net "M_H_CPU0_SB_DQS_DN<9>")
		)
		(pad "95" smd rect
			(at -2.050034 21.67509 270)
			(size 0.519938 1.4986)
			(layers "F.Cu" "F.Mask" "F.Paste")
			(net "GND")
		)
		(pad "96" smd rect
			(at -2.050034 22.524974 270)
			(size 0.519938 1.4986)
			(layers "F.Cu" "F.Mask" "F.Paste")
			(net "M_H_CPU0_SB_CB<0>")
		)
		(pad "97" smd rect
			(at -2.050034 23.375112 270)
			(size 0.519938 1.4986)
			(layers "F.Cu" "F.Mask" "F.Paste")
			(net "GND")
		)
		(pad "98" smd rect
			(at -2.050034 24.224996 270)
			(size 0.519938 1.4986)
			(layers "F.Cu" "F.Mask" "F.Paste")
			(net "M_H_CPU0_SB_CB<1>")
		)
		(pad "99" smd rect
			(at -2.050034 25.07488 270)
			(size 0.519938 1.4986)
			(layers "F.Cu" "F.Mask" "F.Paste")
			(net "GND")
		)
		(pad "100" smd rect
			(at -2.050034 25.925018 270)
			(size 0.519938 1.4986)
			(layers "F.Cu" "F.Mask" "F.Paste")
			(net "M_H_CPU0_SB_DQ<0>")
		)
		(pad "101" smd rect
			(at -2.050034 26.774902 270)
			(size 0.519938 1.4986)
			(layers "F.Cu" "F.Mask" "F.Paste")
			(net "GND")
		)
		(pad "102" smd rect
			(at -2.050034 27.62504 270)
			(size 0.519938 1.4986)
			(layers "F.Cu" "F.Mask" "F.Paste")
			(net "M_H_CPU0_SB_DQ<1>")
		)
		(pad "103" smd rect
			(at -2.050034 28.474924 270)
			(size 0.519938 1.4986)
			(layers "F.Cu" "F.Mask" "F.Paste")
			(net "GND")
		)
		(pad "104" smd rect
			(at -2.050034 29.325062 270)
			(size 0.519938 1.4986)
			(layers "F.Cu" "F.Mask" "F.Paste")
			(net "M_H_CPU0_SB_DQS_DP<0>")
		)
		(pad "105" smd rect
			(at -2.050034 30.174946 270)
			(size 0.519938 1.4986)
			(layers "F.Cu" "F.Mask" "F.Paste")
			(net "M_H_CPU0_SB_DQS_DN<0>")
		)
		(pad "106" smd rect
			(at -2.050034 31.025084 270)
			(size 0.519938 1.4986)
			(layers "F.Cu" "F.Mask" "F.Paste")
			(net "GND")
		)
		(pad "107" smd rect
			(at -2.050034 31.874968 270)
			(size 0.519938 1.4986)
			(layers "F.Cu" "F.Mask" "F.Paste")
			(net "M_H_CPU0_SB_DQ<4>")
		)
		(pad "108" smd rect
			(at -2.050034 32.725106 270)
			(size 0.519938 1.4986)
			(layers "F.Cu" "F.Mask" "F.Paste")
			(net "GND")
		)
		(pad "109" smd rect
			(at -2.050034 33.57499 270)
			(size 0.519938 1.4986)
			(layers "F.Cu" "F.Mask" "F.Paste")
			(net "M_H_CPU0_SB_DQ<5>")
		)
		(pad "110" smd rect
			(at -2.050034 34.425128 270)
			(size 0.519938 1.4986)
			(layers "F.Cu" "F.Mask" "F.Paste")
			(net "GND")
		)
		(pad "111" smd rect
			(at -2.050034 35.275012 270)
			(size 0.519938 1.4986)
			(layers "F.Cu" "F.Mask" "F.Paste")
			(net "M_H_CPU0_SB_DQ<8>")
		)
		(pad "112" smd rect
			(at -2.050034 36.124896 270)
			(size 0.519938 1.4986)
			(layers "F.Cu" "F.Mask" "F.Paste")
			(net "GND")
		)
		(pad "113" smd rect
			(at -2.050034 36.975034 270)
			(size 0.519938 1.4986)
			(layers "F.Cu" "F.Mask" "F.Paste")
			(net "M_H_CPU0_SB_DQ<9>")
		)
		(pad "114" smd rect
			(at -2.050034 37.824918 270)
			(size 0.519938 1.4986)
			(layers "F.Cu" "F.Mask" "F.Paste")
			(net "GND")
		)
		(pad "115" smd rect
			(at -2.050034 38.675056 270)
			(size 0.519938 1.4986)
			(layers "F.Cu" "F.Mask" "F.Paste")
			(net "M_H_CPU0_SB_DQS_DP<1>")
		)
		(pad "116" smd rect
			(at -2.050034 39.52494 270)
			(size 0.519938 1.4986)
			(layers "F.Cu" "F.Mask" "F.Paste")
			(net "M_H_CPU0_SB_DQS_DN<1>")
		)
		(pad "117" smd rect
			(at -2.050034 40.375078 270)
			(size 0.519938 1.4986)
			(layers "F.Cu" "F.Mask" "F.Paste")
			(net "GND")
		)
		(pad "118" smd rect
			(at -2.050034 41.224962 270)
			(size 0.519938 1.4986)
			(layers "F.Cu" "F.Mask" "F.Paste")
			(net "M_H_CPU0_SB_DQ<12>")
		)
		(pad "119" smd rect
			(at -2.050034 42.0751 270)
			(size 0.519938 1.4986)
			(layers "F.Cu" "F.Mask" "F.Paste")
			(net "GND")
		)
		(pad "120" smd rect
			(at -2.050034 42.924984 270)
			(size 0.519938 1.4986)
			(layers "F.Cu" "F.Mask" "F.Paste")
			(net "M_H_CPU0_SB_DQ<13>")
		)
		(pad "121" smd rect
			(at -2.050034 43.775122 270)
			(size 0.519938 1.4986)
			(layers "F.Cu" "F.Mask" "F.Paste")
			(net "GND")
		)
		(pad "122" smd rect
			(at -2.050034 44.625006 270)
			(size 0.519938 1.4986)
			(layers "F.Cu" "F.Mask" "F.Paste")
			(net "M_H_CPU0_SB_DQ<16>")
		)
		(pad "123" smd rect
			(at -2.050034 45.47489 270)
			(size 0.519938 1.4986)
			(layers "F.Cu" "F.Mask" "F.Paste")
			(net "GND")
		)
		(pad "124" smd rect
			(at -2.050034 46.325028 270)
			(size 0.519938 1.4986)
			(layers "F.Cu" "F.Mask" "F.Paste")
			(net "M_H_CPU0_SB_DQ<17>")
		)
		(pad "125" smd rect
			(at -2.050034 47.174912 270)
			(size 0.519938 1.4986)
			(layers "F.Cu" "F.Mask" "F.Paste")
			(net "GND")
		)
		(pad "126" smd rect
			(at -2.050034 48.02505 270)
			(size 0.519938 1.4986)
			(layers "F.Cu" "F.Mask" "F.Paste")
			(net "M_H_CPU0_SB_DQS_DP<2>")
		)
		(pad "127" smd rect
			(at -2.050034 48.874934 270)
			(size 0.519938 1.4986)
			(layers "F.Cu" "F.Mask" "F.Paste")
			(net "M_H_CPU0_SB_DQS_DN<2>")
		)
		(pad "128" smd rect
			(at -2.050034 49.725072 270)
			(size 0.519938 1.4986)
			(layers "F.Cu" "F.Mask" "F.Paste")
			(net "GND")
		)
		(pad "129" smd rect
			(at -2.050034 50.574956 270)
			(size 0.519938 1.4986)
			(layers "F.Cu" "F.Mask" "F.Paste")
			(net "M_H_CPU0_SB_DQ<20>")
		)
		(pad "130" smd rect
			(at -2.050034 51.425094 270)
			(size 0.519938 1.4986)
			(layers "F.Cu" "F.Mask" "F.Paste")
			(net "GND")
		)
		(pad "131" smd rect
			(at -2.050034 52.274978 270)
			(size 0.519938 1.4986)
			(layers "F.Cu" "F.Mask" "F.Paste")
			(net "M_H_CPU0_SB_DQ<21>")
		)
		(pad "132" smd rect
			(at -2.050034 53.125116 270)
			(size 0.519938 1.4986)
			(layers "F.Cu" "F.Mask" "F.Paste")
			(net "GND")
		)
		(pad "133" smd rect
			(at -2.050034 53.975 270)
			(size 0.519938 1.4986)
			(layers "F.Cu" "F.Mask" "F.Paste")
			(net "M_H_CPU0_SB_DQ<24>")
		)
		(pad "134" smd rect
			(at -2.050034 54.824884 270)
			(size 0.519938 1.4986)
			(layers "F.Cu" "F.Mask" "F.Paste")
			(net "GND")
		)
		(pad "135" smd rect
			(at -2.050034 55.675022 270)
			(size 0.519938 1.4986)
			(layers "F.Cu" "F.Mask" "F.Paste")
			(net "M_H_CPU0_SB_DQ<25>")
		)
		(pad "136" smd rect
			(at -2.050034 56.524906 270)
			(size 0.519938 1.4986)
			(layers "F.Cu" "F.Mask" "F.Paste")
			(net "GND")
		)
		(pad "137" smd rect
			(at -2.050034 57.375044 270)
			(size 0.519938 1.4986)
			(layers "F.Cu" "F.Mask" "F.Paste")
			(net "M_H_CPU0_SB_DQS_DP<3>")
		)
	)
)
